(kicad_pcb
	(version 20240108)
	(generator "pcbnew")
	(generator_version "8.0")
	(general
		(thickness 1.62)
		(legacy_teardrops no)
	)
	(paper "A4")
	(title_block
		(title "Jetson Orin Baseboard")
		(date "2025-03-12")
		(rev "1.3.4")
		(company "Antmicro Ltd")
		(comment 1 "www.antmicro.com")
		(comment 9 "footprints 604-608 of 677")
	)
	(layers
		(0 "F.Cu" signal)
		(1 "In1.Cu" signal)
		(2 "In2.Cu" signal)
		(3 "In3.Cu" signal)
		(4 "In4.Cu" jumper)
		(5 "In5.Cu" signal)
		(6 "In6.Cu" signal)
		(31 "B.Cu" signal)
		(32 "B.Adhes" user "B.Adhesive")
		(33 "F.Adhes" user "F.Adhesive")
		(34 "B.Paste" user)
		(35 "F.Paste" user)
		(36 "B.SilkS" user "B.Silkscreen")
		(37 "F.SilkS" user "F.Silkscreen")
		(38 "B.Mask" user)
		(39 "F.Mask" user)
		(40 "Dwgs.User" user "User.Drawings")
		(41 "Cmts.User" user "User.Comments")
		(42 "Eco1.User" user "User.Eco1")
		(43 "Eco2.User" user "User.Eco2")
		(44 "Edge.Cuts" user)
		(45 "Margin" user)
		(46 "B.CrtYd" user "B.Courtyard")
		(47 "F.CrtYd" user "F.Courtyard")
		(48 "B.Fab" user)
		(49 "F.Fab" user)
	)
	(footprint "antmicro-footprints:R_0402_1005Metric"
		(layer "B.Cu")
		(at 109.8 105.4)
		(descr "Resistor SMD 0402")
		(tags "resistor SMD 0402")
		(property "Reference" "R265"
			(at -0.87 0.53 180)
			(layer "B.SilkS")
			(effects
				(font
					(size 0.7 0.7)
					(thickness 0.15)
				)
				(justify left bottom mirror)
			)
		)
		(property "Value" "R_200k_0402"
			(at 0 -1.4 180)
			(layer "B.Fab")
			(effects
				(font
					(size 0.7 0.7)
					(thickness 0.15)
				)
				(justify left bottom mirror)
			)
		)
		(property "Footprint" "antmicro-footprints:R_0402_1005Metric"
			(at 0 0 0)
			(layer "F.Fab")
			(hide yes)
			(effects
				(font
					(size 1.27 1.27)
					(thickness 0.15)
				)
			)
		)
		(property "Datasheet" "https://www.bourns.com/docs/product-datasheets/cr.pdf"
			(at 0 0 0)
			(layer "F.Fab")
			(hide yes)
			(effects
				(font
					(size 1.27 1.27)
					(thickness 0.15)
				)
			)
		)
		(property "Author" "Antmicro"
			(at 0 0 0)
			(layer "B.Fab")
			(hide yes)
			(effects
				(font
					(size 1 1)
					(thickness 0.15)
				)
				(justify mirror)
			)
		)
		(property "License" "Apache-2.0"
			(at 0 0 0)
			(layer "B.Fab")
			(hide yes)
			(effects
				(font
					(size 1 1)
					(thickness 0.15)
				)
				(justify mirror)
			)
		)
		(property "MPN" "CR0402-FX-2003GLF"
			(at 0 0 0)
			(layer "B.Fab")
			(hide yes)
			(effects
				(font
					(size 1 1)
					(thickness 0.15)
				)
				(justify mirror)
			)
		)
		(property "Manufacturer" "Bourns"
			(at 0 0 0)
			(layer "B.Fab")
			(hide yes)
			(effects
				(font
					(size 1 1)
					(thickness 0.15)
				)
				(justify mirror)
			)
		)
		(property "Tolerance" "1%"
			(at 0 0 0)
			(layer "B.Fab")
			(hide yes)
			(effects
				(font
					(size 1 1)
					(thickness 0.15)
				)
				(justify mirror)
			)
		)
		(property "Val" "200k"
			(at 0 0 0)
			(layer "B.Fab")
			(hide yes)
			(effects
				(font
					(size 1 1)
					(thickness 0.15)
				)
				(justify mirror)
			)
		)
		(sheetname "USB3")
		(sheetfile "usb3.kicad_sch")
		(attr smd)
		(fp_rect
			(start -0.925 0.47)
			(end 0.925 -0.47)
			(stroke
				(width 0.05)
				(type default)
			)
			(fill none)
			(layer "B.CrtYd")
		)
		(fp_rect
			(start -0.5 0.25)
			(end 0.5 -0.25)
			(stroke
				(width 0.15)
				(type solid)
			)
			(fill none)
			(layer "B.Fab")
		)
		(fp_text user "Author: Antmicro"
			(at -0.95 -4.169 180)
			(layer "B.Fab")
			(hide yes)
			(effects
				(font
					(size 0.7 0.7)
					(thickness 0.15)
				)
				(justify left bottom mirror)
			)
		)
		(fp_text user "${REFERENCE}"
			(at -0.95 -3.168 180)
			(layer "B.Fab")
			(hide yes)
			(effects
				(font
					(size 0.7 0.7)
					(thickness 0.15)
				)
				(justify left bottom mirror)
			)
		)
		(fp_text user "License: Apache-2.0"
			(at -0.95 -5.169 180)
			(layer "B.Fab")
			(hide yes)
			(effects
				(font
					(size 0.7 0.7)
					(thickness 0.15)
				)
				(justify left bottom mirror)
			)
		)
		(pad "1" smd roundrect
			(at -0.48 0)
			(size 0.59 0.64)
			(layers "B.Cu" "B.Paste" "B.Mask")
			(roundrect_rratio 0.25)
			(net 87 "+3V3")
			(pintype "passive")
		)
		(pad "2" smd roundrect
			(at 0.48 0)
			(size 0.59 0.64)
			(layers "B.Cu" "B.Paste" "B.Mask")
			(roundrect_rratio 0.25)
			(net 362 "/USB3/USBC1_I2C_SDA")
			(pintype "passive")
		)
	)
	(footprint "antmicro-footprints:SOIC-4_4.55x2.6mm_P1.27mm"
		(layer "B.Cu")
		(at 56.625 101.925 90)
		(descr "ACPL-217-500E")
		(tags "Integrated Circuit")
		(property "Reference" "U39"
			(at -1.185 -1.535 90)
			(layer "B.SilkS")
			(effects
				(font
					(size 0.7 0.7)
					(thickness 0.15)
				)
				(justify right bottom mirror)
			)
		)
		(property "Value" "ACPL-217-500E"
			(at -4.25 -2.75 90)
			(layer "B.Fab")
			(effects
				(font
					(size 0.7 0.7)
					(thickness 0.15)
				)
				(justify right bottom mirror)
			)
		)
		(property "Footprint" "antmicro-footprints:SOIC-4_4.55x2.6mm_P1.27mm"
			(at 0 0 90)
			(layer "F.Fab")
			(hide yes)
			(effects
				(font
					(size 1.27 1.27)
					(thickness 0.15)
				)
			)
		)
		(property "Datasheet" "https://docs.broadcom.com/doc/AV02-0470EN"
			(at 0 0 90)
			(layer "F.Fab")
			(hide yes)
			(effects
				(font
					(size 1.27 1.27)
					(thickness 0.15)
				)
			)
		)
		(property "Description" "Broadcom ACPL-217-500E DC Input Transistor Output Optocoupler, Surface Mount, 4-Pin SO"
			(at 158.55 45.3 0)
			(layer "F.Fab")
			(hide yes)
			(effects
				(font
					(size 1.27 1.27)
					(thickness 0.15)
				)
			)
		)
		(property "Author" "Antmicro"
			(at 158.55 45.3 0)
			(layer "B.Fab")
			(hide yes)
			(effects
				(font
					(size 1 1)
					(thickness 0.15)
				)
				(justify mirror)
			)
		)
		(property "License" "Apache-2.0"
			(at 158.55 45.3 0)
			(layer "B.Fab")
			(hide yes)
			(effects
				(font
					(size 1 1)
					(thickness 0.15)
				)
				(justify mirror)
			)
		)
		(property "MPN" "ACPL-217-500E"
			(at 158.55 45.3 0)
			(layer "B.Fab")
			(hide yes)
			(effects
				(font
					(size 1 1)
					(thickness 0.15)
				)
				(justify mirror)
			)
		)
		(property "Manufacturer" "Broadcom"
			(at 158.55 45.3 0)
			(layer "B.Fab")
			(hide yes)
			(effects
				(font
					(size 1 1)
					(thickness 0.15)
				)
				(justify mirror)
			)
		)
		(sheetname "Ethernet")
		(sheetfile "ethernet.kicad_sch")
		(attr smd)
		(fp_line
			(start 2.3 -1.4)
			(end 2.3 -1.1)
			(stroke
				(width 0.12)
				(type solid)
			)
			(layer "B.SilkS")
		)
		(fp_line
			(start 1.8 -1.4)
			(end 2.3 -1.4)
			(stroke
				(width 0.12)
				(type solid)
			)
			(layer "B.SilkS")
		)
		(fp_line
			(start -2.3 -1.4)
			(end -1.8 -1.4)
			(stroke
				(width 0.12)
				(type solid)
			)
			(layer "B.SilkS")
		)
		(fp_line
			(start -2.3 -1.4)
			(end -2.3 -1.1)
			(stroke
				(width 0.12)
				(type solid)
			)
			(layer "B.SilkS")
		)
		(fp_line
			(start 2.3 1.4)
			(end 2.3 1.1)
			(stroke
				(width 0.12)
				(type solid)
			)
			(layer "B.SilkS")
		)
		(fp_line
			(start 2.3 1.4)
			(end 1.8 1.4)
			(stroke
				(width 0.12)
				(type solid)
			)
			(layer "B.SilkS")
		)
		(fp_line
			(start -1.8 1.4)
			(end -2.3 1.4)
			(stroke
				(width 0.12)
				(type solid)
			)
			(layer "B.SilkS")
		)
		(fp_line
			(start 4.29 -1.69)
			(end 4.29 1.7)
			(stroke
				(width 0.05)
				(type solid)
			)
			(layer "B.CrtYd")
		)
		(fp_line
			(start -4.3 -1.69)
			(end 4.29 -1.69)
			(stroke
				(width 0.05)
				(type solid)
			)
			(layer "B.CrtYd")
		)
		(fp_line
			(start 4.29 1.7)
			(end -4.3 1.7)
			(stroke
				(width 0.05)
				(type solid)
			)
			(layer "B.CrtYd")
		)
		(fp_line
			(start -4.3 1.7)
			(end -4.3 -1.69)
			(stroke
				(width 0.05)
				(type solid)
			)
			(layer "B.CrtYd")
		)
		(fp_line
			(start 2.2 -1.3)
			(end 2.2 1.301)
			(stroke
				(width 0.15)
				(type solid)
			)
			(layer "B.Fab")
		)
		(fp_line
			(start -2.201 -1.3)
			(end 2.2 -1.3)
			(stroke
				(width 0.15)
				(type solid)
			)
			(layer "B.Fab")
		)
		(fp_line
			(start 2.2 1.301)
			(end -2.201 1.301)
			(stroke
				(width 0.15)
				(type solid)
			)
			(layer "B.Fab")
		)
		(fp_line
			(start -0.931 1.301)
			(end -2.201 0.03)
			(stroke
				(width 0.15)
				(type solid)
			)
			(layer "B.Fab")
		)
		(fp_line
			(start -2.201 1.301)
			(end -2.201 -1.3)
			(stroke
				(width 0.15)
				(type solid)
			)
			(layer "B.Fab")
		)
		(fp_text user "."
			(at -2.7 1.6 90)
			(layer "B.SilkS")
			(effects
				(font
					(size 1 1)
					(thickness 0.15)
				)
				(justify mirror)
			)
		)
		(fp_text user "${REFERENCE}"
			(at -4.3 -4.25 90)
			(layer "B.Fab")
			(hide yes)
			(effects
				(font
					(size 0.7 0.7)
					(thickness 0.15)
				)
				(justify right bottom mirror)
			)
		)
		(fp_text user "Author: Antmicro"
			(at -4.3 -5.5 90)
			(layer "B.Fab")
			(hide yes)
			(effects
				(font
					(size 0.7 0.7)
					(thickness 0.15)
				)
				(justify right bottom mirror)
			)
		)
		(fp_text user "License: Apache-2.0"
			(at -4.25 -7 90)
			(layer "B.Fab")
			(hide yes)
			(effects
				(font
					(size 0.7 0.7)
					(thickness 0.15)
				)
				(justify right bottom mirror)
			)
		)
		(pad "1" smd roundrect
			(at -3.125 0.635)
			(size 0.65 1.85)
			(layers "B.Cu" "B.Paste" "B.Mask")
			(roundrect_rratio 0.15)
			(net 514 "DISABLE_POE_DCDC")
			(pintype "passive")
		)
		(pad "2" smd roundrect
			(at -3.125 -0.634)
			(size 0.65 1.85)
			(layers "B.Cu" "B.Paste" "B.Mask")
			(roundrect_rratio 0.15)
			(net 731 "Net-(R156-Pad1)")
			(pintype "passive")
		)
		(pad "3" smd roundrect
			(at 3.124 -0.634)
			(size 0.65 1.85)
			(layers "B.Cu" "B.Paste" "B.Mask")
			(roundrect_rratio 0.15)
			(net 730 "Net-(R155-Pad2)")
			(pintype "passive")
		)
		(pad "4" smd roundrect
			(at 3.124 0.635)
			(size 0.65 1.85)
			(layers "B.Cu" "B.Paste" "B.Mask")
			(roundrect_rratio 0.15)
			(net 127 "/Ethernet/POE_ACTIVE")
			(pintype "passive")
		)
	)
	(footprint "antmicro-footprints:TP_SMD_0.75mm"
		(layer "B.Cu")
		(at 130.085 87.77)
		(property "Reference" "TP11"
			(at 0.395 0.365001 0)
			(layer "B.SilkS")
			(effects
				(font
					(size 0.7 0.7)
					(thickness 0.15)
				)
				(justify right bottom mirror)
			)
		)
		(property "Value" "TP_0.75mm_SMD"
			(at 0 -1.2 0)
			(layer "B.Fab")
			(effects
				(font
					(size 0.7 0.7)
					(thickness 0.15)
				)
				(justify right bottom mirror)
			)
		)
		(property "Footprint" "antmicro-footprints:TP_SMD_0.75mm"
			(at 0 0 0)
			(layer "F.Fab")
			(hide yes)
			(effects
				(font
					(size 1.27 1.27)
					(thickness 0.15)
				)
			)
		)
		(property "Author" "Antmicro"
			(at 0 0 0)
			(layer "B.Fab")
			(hide yes)
			(effects
				(font
					(size 1 1)
					(thickness 0.15)
				)
				(justify mirror)
			)
		)
		(property "License" "Apache-2.0"
			(at 0 0 0)
			(layer "B.Fab")
			(hide yes)
			(effects
				(font
					(size 1 1)
					(thickness 0.15)
				)
				(justify mirror)
			)
		)
		(property "MPN" ""
			(at 0 0 0)
			(layer "B.Fab")
			(hide yes)
			(effects
				(font
					(size 1 1)
					(thickness 0.15)
				)
				(justify mirror)
			)
		)
		(property "Manufacturer" ""
			(at 0 0 0)
			(layer "B.Fab")
			(hide yes)
			(effects
				(font
					(size 1 1)
					(thickness 0.15)
				)
				(justify mirror)
			)
		)
		(sheetname "M.2")
		(sheetfile "m-2.kicad_sch")
		(attr exclude_from_pos_files exclude_from_bom)
		(fp_circle
			(center 0 0)
			(end 0.475 0)
			(stroke
				(width 0.05)
				(type default)
			)
			(fill none)
			(layer "B.CrtYd")
		)
		(fp_text user "Author: Antmicro"
			(at -0.4 -3.901 0)
			(layer "B.Fab")
			(hide yes)
			(effects
				(font
					(size 0.7 0.7)
					(thickness 0.15)
				)
				(justify right bottom mirror)
			)
		)
		(fp_text user "${REFERENCE}"
			(at -0.4 -2.7 0)
			(layer "B.Fab")
			(hide yes)
			(effects
				(font
					(size 0.7 0.7)
					(thickness 0.15)
				)
				(justify right bottom mirror)
			)
		)
		(fp_text user "License: Apache-2.0"
			(at -0.4 -5.101 0)
			(layer "B.Fab")
			(hide yes)
			(effects
				(font
					(size 0.7 0.7)
					(thickness 0.15)
				)
				(justify right bottom mirror)
			)
		)
		(pad "1" smd circle
			(at 0 0)
			(size 0.75 0.75)
			(layers "B.Cu" "B.Mask")
			(net 245 "/M.2/M2_M_SMB_DATA")
			(pinfunction "1")
			(pintype "passive")
		)
	)
	(footprint "antmicro-footprints:C_0402_1005Metric"
		(layer "B.Cu")
		(at 133.45 117.55)
		(descr "Capacitor SMD 0402")
		(tags "capacitor SMD 0402")
		(property "Reference" "C43"
			(at -0.8 0.45 180)
			(layer "B.SilkS")
			(effects
				(font
					(size 0.7 0.7)
					(thickness 0.15)
				)
				(justify left bottom mirror)
			)
		)
		(property "Value" "C_100n_0402"
			(at 0 -1.4 180)
			(layer "B.Fab")
			(effects
				(font
					(size 0.7 0.7)
					(thickness 0.15)
				)
				(justify left bottom mirror)
			)
		)
		(property "Footprint" "antmicro-footprints:C_0402_1005Metric"
			(at 0 0 0)
			(layer "F.Fab")
			(hide yes)
			(effects
				(font
					(size 1.27 1.27)
					(thickness 0.15)
				)
			)
		)
		(property "Datasheet" "https://www.murata.com/products/productdetail?partno=GRM155R61H104KE14%23"
			(at 0 0 0)
			(layer "F.Fab")
			(hide yes)
			(effects
				(font
					(size 1.27 1.27)
					(thickness 0.15)
				)
			)
		)
		(property "Author" "Antmicro"
			(at 0 0 0)
			(layer "B.Fab")
			(hide yes)
			(effects
				(font
					(size 1 1)
					(thickness 0.15)
				)
				(justify mirror)
			)
		)
		(property "Dielectric" "X5R"
			(at 0 0 0)
			(layer "B.Fab")
			(hide yes)
			(effects
				(font
					(size 1 1)
					(thickness 0.15)
				)
				(justify mirror)
			)
		)
		(property "License" "Apache-2.0"
			(at 0 0 0)
			(layer "B.Fab")
			(hide yes)
			(effects
				(font
					(size 1 1)
					(thickness 0.15)
				)
				(justify mirror)
			)
		)
		(property "MPN" "GRM155R61H104KE14D"
			(at 0 0 0)
			(layer "B.Fab")
			(hide yes)
			(effects
				(font
					(size 1 1)
					(thickness 0.15)
				)
				(justify mirror)
			)
		)
		(property "Manufacturer" "Murata"
			(at 0 0 0)
			(layer "B.Fab")
			(hide yes)
			(effects
				(font
					(size 1 1)
					(thickness 0.15)
				)
				(justify mirror)
			)
		)
		(property "Val" "100n"
			(at 0 0 0)
			(layer "B.Fab")
			(hide yes)
			(effects
				(font
					(size 1 1)
					(thickness 0.15)
				)
				(justify mirror)
			)
		)
		(property "Voltage" "50V"
			(at 0 0 0)
			(layer "B.Fab")
			(hide yes)
			(effects
				(font
					(size 1 1)
					(thickness 0.15)
				)
				(justify mirror)
			)
		)
		(sheetname "CSI")
		(sheetfile "csi.kicad_sch")
		(attr smd)
		(fp_rect
			(start -0.925 0.47)
			(end 0.925 -0.47)
			(stroke
				(width 0.05)
				(type default)
			)
			(fill none)
			(layer "B.CrtYd")
		)
		(fp_line
			(start -0.494 -0.248)
			(end 0.504 -0.248)
			(stroke
				(width 0.15)
				(type solid)
			)
			(layer "B.Fab")
		)
		(fp_line
			(start -0.494 0.25)
			(end -0.494 -0.248)
			(stroke
				(width 0.15)
				(type solid)
			)
			(layer "B.Fab")
		)
		(fp_line
			(start 0.504 -0.248)
			(end 0.504 0.25)
			(stroke
				(width 0.15)
				(type solid)
			)
			(layer "B.Fab")
		)
		(fp_line
			(start 0.504 0.25)
			(end -0.494 0.25)
			(stroke
				(width 0.15)
				(type solid)
			)
			(layer "B.Fab")
		)
		(fp_text user "Author: Antmicro"
			(at -0.932 -4.17 180)
			(layer "B.Fab")
			(hide yes)
			(effects
				(font
					(size 0.7 0.7)
					(thickness 0.15)
				)
				(justify left bottom mirror)
			)
		)
		(fp_text user "${REFERENCE}"
			(at -0.932 -3.168 180)
			(layer "B.Fab")
			(hide yes)
			(effects
				(font
					(size 0.7 0.7)
					(thickness 0.15)
				)
				(justify left bottom mirror)
			)
		)
		(fp_text user "License: Apache-2.0"
			(at -0.932 -5.17 180)
			(layer "B.Fab")
			(hide yes)
			(effects
				(font
					(size 0.7 0.7)
					(thickness 0.15)
				)
				(justify left bottom mirror)
			)
		)
		(pad "1" smd roundrect
			(at -0.48 0)
			(size 0.59 0.64)
			(layers "B.Cu" "B.Paste" "B.Mask")
			(roundrect_rratio 0.25)
			(net 87 "+3V3")
			(pintype "passive")
		)
		(pad "2" smd roundrect
			(at 0.48 0)
			(size 0.59 0.64)
			(layers "B.Cu" "B.Paste" "B.Mask")
			(roundrect_rratio 0.25)
			(net 1 "GND")
			(pintype "passive")
		)
	)
	(footprint "antmicro-footprints:R_0402_1005Metric"
		(layer "B.Cu")
		(at 140.7 123)
		(descr "Resistor SMD 0402")
		(tags "resistor SMD 0402")
		(property "Reference" "R189"
			(at 2 -1.425 0)
			(layer "B.SilkS")
			(effects
				(font
					(size 0.7 0.7)
					(thickness 0.15)
				)
				(justify left bottom mirror)
			)
		)
		(property "Value" "R_10k_0402"
			(at 0 -1.4 180)
			(layer "B.Fab")
			(effects
				(font
					(size 0.7 0.7)
					(thickness 0.15)
				)
				(justify left bottom mirror)
			)
		)
		(property "Footprint" "antmicro-footprints:R_0402_1005Metric"
			(at 0 0 0)
			(layer "F.Fab")
			(hide yes)
			(effects
				(font
					(size 1.27 1.27)
					(thickness 0.15)
				)
			)
		)
		(property "Datasheet" "https://www.bourns.com/docs/product-datasheets/cr.pdf"
			(at 0 0 0)
			(layer "F.Fab")
			(hide yes)
			(effects
				(font
					(size 1.27 1.27)
					(thickness 0.15)
				)
			)
		)
		(property "Author" "Antmicro"
			(at 0 0 0)
			(layer "B.Fab")
			(hide yes)
			(effects
				(font
					(size 1 1)
					(thickness 0.15)
				)
				(justify mirror)
			)
		)
		(property "License" "Apache-2.0"
			(at 0 0 0)
			(layer "B.Fab")
			(hide yes)
			(effects
				(font
					(size 1 1)
					(thickness 0.15)
				)
				(justify mirror)
			)
		)
		(property "MPN" "CR0402-FX-1002GLF"
			(at 0 0 0)
			(layer "B.Fab")
			(hide yes)
			(effects
				(font
					(size 1 1)
					(thickness 0.15)
				)
				(justify mirror)
			)
		)
		(property "Manufacturer" "Bourns"
			(at 0 0 0)
			(layer "B.Fab")
			(hide yes)
			(effects
				(font
					(size 1 1)
					(thickness 0.15)
				)
				(justify mirror)
			)
		)
		(property "Tolerance" "1%"
			(at 0 0 0)
			(layer "B.Fab")
			(hide yes)
			(effects
				(font
					(size 1 1)
					(thickness 0.15)
				)
				(justify mirror)
			)
		)
		(property "Val" "10k"
			(at 0 0 0)
			(layer "B.Fab")
			(hide yes)
			(effects
				(font
					(size 1 1)
					(thickness 0.15)
				)
				(justify mirror)
			)
		)
		(sheetname "Peripherals")
		(sheetfile "peripherals.kicad_sch")
		(attr smd)
		(fp_rect
			(start -0.925 0.47)
			(end 0.925 -0.47)
			(stroke
				(width 0.05)
				(type default)
			)
			(fill none)
			(layer "B.CrtYd")
		)
		(fp_rect
			(start -0.5 0.25)
			(end 0.5 -0.25)
			(stroke
				(width 0.15)
				(type solid)
			)
			(fill none)
			(layer "B.Fab")
		)
		(fp_text user "Author: Antmicro"
			(at -0.95 -4.169 180)
			(layer "B.Fab")
			(hide yes)
			(effects
				(font
					(size 0.7 0.7)
					(thickness 0.15)
				)
				(justify left bottom mirror)
			)
		)
		(fp_text user "${REFERENCE}"
			(at -0.95 -3.168 180)
			(layer "B.Fab")
			(hide yes)
			(effects
				(font
					(size 0.7 0.7)
					(thickness 0.15)
				)
				(justify left bottom mirror)
			)
		)
		(fp_text user "License: Apache-2.0"
			(at -0.95 -5.169 180)
			(layer "B.Fab")
			(hide yes)
			(effects
				(font
					(size 0.7 0.7)
					(thickness 0.15)
				)
				(justify left bottom mirror)
			)
		)
		(pad "1" smd roundrect
			(at -0.48 0)
			(size 0.59 0.64)
			(layers "B.Cu" "B.Paste" "B.Mask")
			(roundrect_rratio 0.25)
			(net 658 "/Peripherals/I2C_CONN_PEN")
			(pintype "passive")
		)
		(pad "2" smd roundrect
			(at 0.48 0)
			(size 0.59 0.64)
			(layers "B.Cu" "B.Paste" "B.Mask")
			(roundrect_rratio 0.25)
			(net 87 "+3V3")
			(pintype "passive")
		)
	)
)
